(kicad_pcb
	(version 20260206)
	(generator "pcbnew")
	(generator_version "10.0")
	(general
		(thickness 1.6)
		(legacy_teardrops no)
	)
	(paper "A4")
	(title_block
		(title "01162023_DA0F0TEBIF0_F0T_Expander_BD_F_brd_V02_OCP.brd")
		(comment 1 "Grand Teton / footprints 8687-8692 of 9728")
	)
	(layers
		(0 "F.Cu" signal "TOP")
		(4 "In1.Cu" signal "GND")
		(6 "In2.Cu" signal "VCC")
		(8 "In3.Cu" signal "VCC1")
		(10 "In4.Cu" signal "GND1")
		(12 "In5.Cu" signal "IN1")
		(14 "In6.Cu" signal "GND2")
		(16 "In7.Cu" signal "IN2")
		(18 "In8.Cu" signal "GND3")
		(20 "In9.Cu" signal "IN3")
		(22 "In10.Cu" signal "GND4")
		(24 "In11.Cu" signal "IN4")
		(26 "In12.Cu" signal "GND5")
		(28 "In13.Cu" signal "IN5")
		(30 "In14.Cu" signal "GND6")
		(32 "In15.Cu" signal "IN6")
		(34 "In16.Cu" signal "GND7")
		(2 "B.Cu" signal "BOTTOM")
		(9 "F.Adhes" user "F.Adhesive")
		(11 "B.Adhes" user "B.Adhesive")
		(13 "F.Paste" user "Package Geometry/Pastemask Top")
		(15 "B.Paste" user "Package Geometry/Pastemask Bottom")
		(5 "F.SilkS" user "Ref Des/Silkscreen Top")
		(7 "B.SilkS" user "Ref Des/Silkscreen Bottom")
		(1 "F.Mask" user "Board Geometry/Soldermask Top")
		(3 "B.Mask" user "Board Geometry/Soldermask Bottom")
		(17 "Dwgs.User" user "User.Drawings")
		(19 "Cmts.User" user "User.Comments")
		(21 "Eco1.User" user "User.Eco1")
		(23 "Eco2.User" user "User.Eco2")
		(25 "Edge.Cuts" user "Board Geometry/Outline")
		(27 "Margin" user)
		(31 "F.CrtYd" user "Package Geometry/Place Bound Top")
		(29 "B.CrtYd" user "Package Geometry/Place Bound Bottom")
		(35 "F.Fab" user "Ref Des/Assembly Top")
		(33 "B.Fab" user "Ref Des/Assembly Bottom")
	)
	(footprint ""
		(layer "B.Cu")
		(at 368.018314 -227.084382 90)
		(property "Reference" "U68"
			(at 4.533392 0.149098 0)
			(unlocked yes)
			(layer "B.SilkS")
			(effects
				(font
					(size 0.7874 0.5842)
					(thickness 0.1524)
				)
				(justify mirror)
			)
		)
		(property "Value" ""
			(at 0 0 90)
			(layer "B.Fab")
			(effects
				(font
					(size 1.27 1.27)
				)
				(justify mirror)
			)
		)
		(duplicate_pad_numbers_are_jumpers no)
		(fp_line
			(start 1.8288 -2.4892)
			(end 0.5588 -2.4892)
			(stroke
				(width 0.1524)
				(type default)
			)
			(layer "B.SilkS")
		)
		(fp_line
			(start 0.5588 -2.4892)
			(end 0 -1.9304)
			(stroke
				(width 0.1524)
				(type default)
			)
			(layer "B.SilkS")
		)
		(fp_line
			(start -0.5588 -2.4892)
			(end -1.8288 -2.4892)
			(stroke
				(width 0.1524)
				(type default)
			)
			(layer "B.SilkS")
		)
		(fp_line
			(start -1.8288 -2.4892)
			(end -1.8161 2.4892)
			(stroke
				(width 0.1524)
				(type default)
			)
			(layer "B.SilkS")
		)
		(fp_line
			(start 0 -1.9304)
			(end -0.5588 -2.4892)
			(stroke
				(width 0.1524)
				(type default)
			)
			(layer "B.SilkS")
		)
		(fp_line
			(start 1.8288 2.4892)
			(end 1.8288 -2.4892)
			(stroke
				(width 0.1524)
				(type default)
			)
			(layer "B.SilkS")
		)
		(fp_line
			(start -1.8161 2.4892)
			(end 1.8288 2.4892)
			(stroke
				(width 0.1524)
				(type default)
			)
			(layer "B.SilkS")
		)
		(fp_poly
			(pts
				(xy 4.23672 -1.989328) (xy 4.23672 -2.614168) (xy 3.683 -2.286)
			)
			(stroke
				(width 0)
				(type default)
			)
			(fill yes)
			(layer "B.SilkS")
		)
		(fp_line
			(start 1.9939 -2.4892)
			(end -1.9939 -2.4892)
			(stroke
				(width 0.1)
				(type default)
			)
			(layer "B.Fab")
		)
		(fp_line
			(start -1.9939 -2.4892)
			(end -1.9939 -2.3876)
			(stroke
				(width 0.1)
				(type default)
			)
			(layer "B.Fab")
		)
		(fp_line
			(start 3.0988 -2.3876)
			(end 1.9939 -2.3876)
			(stroke
				(width 0.1)
				(type default)
			)
			(layer "B.Fab")
		)
		(fp_line
			(start 1.9939 -2.3876)
			(end 1.9939 -2.4892)
			(stroke
				(width 0.1)
				(type default)
			)
			(layer "B.Fab")
		)
		(fp_line
			(start 1.9939 -2.3876)
			(end 1.9812 -2.3876)
			(stroke
				(width 0.1)
				(type default)
			)
			(layer "B.Fab")
		)
		(fp_line
			(start -1.9939 -2.3876)
			(end -3.0988 -2.3876)
			(stroke
				(width 0.1)
				(type default)
			)
			(layer "B.Fab")
		)
		(fp_line
			(start -1.9939 -2.3876)
			(end -1.9939 2.3876)
			(stroke
				(width 0.1)
				(type default)
			)
			(layer "B.Fab")
		)
		(fp_line
			(start -3.0988 -2.3876)
			(end -3.0988 2.3876)
			(stroke
				(width 0.1)
				(type default)
			)
			(layer "B.Fab")
		)
		(fp_line
			(start -3.0988 -2.3876)
			(end -3.0988 2.3876)
			(stroke
				(width 0.1)
				(type default)
			)
			(layer "B.Fab")
		)
		(fp_line
			(start 3.0988 2.3876)
			(end 3.0988 -2.3876)
			(stroke
				(width 0.1)
				(type default)
			)
			(layer "B.Fab")
		)
		(fp_line
			(start 3.0988 2.3876)
			(end 3.0988 -2.3876)
			(stroke
				(width 0.1)
				(type default)
			)
			(layer "B.Fab")
		)
		(fp_line
			(start 1.9939 2.3876)
			(end 1.9939 -2.3876)
			(stroke
				(width 0.1)
				(type default)
			)
			(layer "B.Fab")
		)
		(fp_line
			(start 1.9939 2.3876)
			(end 3.0988 2.3876)
			(stroke
				(width 0.1)
				(type default)
			)
			(layer "B.Fab")
		)
		(fp_line
			(start -1.9939 2.3876)
			(end -1.9939 2.4892)
			(stroke
				(width 0.1)
				(type default)
			)
			(layer "B.Fab")
		)
		(fp_line
			(start -3.0988 2.3876)
			(end -1.9939 2.3876)
			(stroke
				(width 0.1)
				(type default)
			)
			(layer "B.Fab")
		)
		(fp_line
			(start 1.9939 2.4892)
			(end 1.9939 2.3876)
			(stroke
				(width 0.1)
				(type default)
			)
			(layer "B.Fab")
		)
		(fp_line
			(start -1.9939 2.4892)
			(end 1.9939 2.4892)
			(stroke
				(width 0.1)
				(type default)
			)
			(layer "B.Fab")
		)
		(fp_line
			(start -1.9939 2.4892)
			(end -2.0066 2.4892)
			(stroke
				(width 0.1)
				(type default)
			)
			(layer "B.Fab")
		)
		(fp_line
			(start -1.9939 2.5019)
			(end -1.9939 2.4892)
			(stroke
				(width 0.1)
				(type default)
			)
			(layer "B.Fab")
		)
		(fp_poly
			(pts
				(xy 4.23672 -1.989328) (xy 4.23672 -2.614168) (xy 3.683 -2.286)
			)
			(stroke
				(width 0)
				(type default)
			)
			(fill yes)
			(layer "B.Fab")
		)
		(pad "1" smd rect
			(at 2.7432 -2.2225)
			(size 0.3556 1.5494)
			(layers "B.Cu" "B.Mask" "B.Paste")
			(net "SEL_FLASH_PEX3_BUF_R")
		)
		(pad "2" smd rect
			(at 2.7432 -1.5875)
			(size 0.3556 1.5494)
			(layers "B.Cu" "B.Mask" "B.Paste")
			(net "SPI_PEX3_CS_R_N")
		)
		(pad "3" smd rect
			(at 2.7432 -0.9525)
			(size 0.3556 1.5494)
			(layers "B.Cu" "B.Mask" "B.Paste")
			(net "SPI_BIC1_CS0_LS23_R2_N")
		)
		(pad "4" smd rect
			(at 2.7432 -0.3175)
			(size 0.3556 1.5494)
			(layers "B.Cu" "B.Mask" "B.Paste")
			(net "SPI_PEX3_CS_MUX_N")
		)
		(pad "5" smd rect
			(at 2.7432 0.3175)
			(size 0.3556 1.5494)
			(layers "B.Cu" "B.Mask" "B.Paste")
			(net "SPI_PEX3_CLK_R")
		)
		(pad "6" smd rect
			(at 2.7432 0.9525)
			(size 0.3556 1.5494)
			(layers "B.Cu" "B.Mask" "B.Paste")
			(net "SPI_BIC1_CLK_LS23_R2")
		)
		(pad "7" smd rect
			(at 2.7432 1.5875)
			(size 0.3556 1.5494)
			(layers "B.Cu" "B.Mask" "B.Paste")
			(net "SPI_PEX3_CLK_MUX")
		)
		(pad "8" smd rect
			(at 2.7432 2.2225)
			(size 0.3556 1.5494)
			(layers "B.Cu" "B.Mask" "B.Paste")
			(net "GND")
		)
		(pad "9" smd rect
			(at -2.7432 2.2225)
			(size 0.3556 1.5494)
			(layers "B.Cu" "B.Mask" "B.Paste")
			(net "SPI_PEX3_SDIO0_MUX")
		)
		(pad "10" smd rect
			(at -2.7432 1.5875)
			(size 0.3556 1.5494)
			(layers "B.Cu" "B.Mask" "B.Paste")
			(net "SPI_BIC1_MOSI_LS23_R2")
		)
		(pad "11" smd rect
			(at -2.7432 0.9525)
			(size 0.3556 1.5494)
			(layers "B.Cu" "B.Mask" "B.Paste")
			(net "SPI_PEX3_SDIO0_R")
		)
		(pad "12" smd rect
			(at -2.7432 0.3175)
			(size 0.3556 1.5494)
			(layers "B.Cu" "B.Mask" "B.Paste")
			(net "SPI_PEX3_SDIO1_MUX")
		)
		(pad "13" smd rect
			(at -2.7432 -0.3175)
			(size 0.3556 1.5494)
			(layers "B.Cu" "B.Mask" "B.Paste")
			(net "SPI_BIC1_MISO_LS23_R2")
		)
		(pad "14" smd rect
			(at -2.7432 -0.9525)
			(size 0.3556 1.5494)
			(layers "B.Cu" "B.Mask" "B.Paste")
			(net "SPI_PEX3_SDIO1_R")
		)
		(pad "15" smd rect
			(at -2.7432 -1.5875)
			(size 0.3556 1.5494)
			(layers "B.Cu" "B.Mask" "B.Paste")
			(net "SPI_MUX_PEX3_EN_N")
		)
		(pad "16" smd rect
			(at -2.7432 -2.2225)
			(size 0.3556 1.5494)
			(layers "B.Cu" "B.Mask" "B.Paste")
			(net "P3V3_AUX")
		)
	)
	(footprint ""
		(layer "B.Cu")
		(at 414.599882 -299.699934 -90)
		(property "Reference" "C1949"
			(at 0 0 90)
			(layer "B.SilkS")
			(hide yes)
			(effects
				(font
					(size 1.27 1.27)
				)
				(justify mirror)
			)
		)
		(property "Value" ""
			(at 0 0 90)
			(layer "B.Fab")
			(effects
				(font
					(size 1.27 1.27)
				)
				(justify mirror)
			)
		)
		(duplicate_pad_numbers_are_jumpers no)
		(fp_line
			(start -0.299974 0.150114)
			(end 0.299974 0.150114)
			(stroke
				(width 0.1)
				(type default)
			)
			(layer "B.Fab")
		)
		(fp_line
			(start 0.299974 0.150114)
			(end 0.299974 -0.150114)
			(stroke
				(width 0.1)
				(type default)
			)
			(layer "B.Fab")
		)
		(fp_line
			(start -0.299974 -0.150114)
			(end -0.299974 0.150114)
			(stroke
				(width 0.1)
				(type default)
			)
			(layer "B.Fab")
		)
		(fp_line
			(start 0.299974 -0.150114)
			(end -0.299974 -0.150114)
			(stroke
				(width 0.1)
				(type default)
			)
			(layer "B.Fab")
		)
		(pad "1" smd rect
			(at 0.2667 0 90)
			(size 0.3048 0.381)
			(layers "B.Cu" "B.Mask" "B.Paste")
			(net "P0V8_SERDES_VDDA_PEX3")
		)
		(pad "2" smd rect
			(at -0.2667 0 90)
			(size 0.3048 0.381)
			(layers "B.Cu" "B.Mask" "B.Paste")
			(net "GND")
		)
	)
	(footprint ""
		(layer "B.Cu")
		(at 280.020268 -302.028606)
		(property "Reference" "C3336"
			(at 0 0 0)
			(layer "B.SilkS")
			(hide yes)
			(effects
				(font
					(size 1.27 1.27)
				)
				(justify mirror)
			)
		)
		(property "Value" ""
			(at 0 0 0)
			(layer "B.Fab")
			(effects
				(font
					(size 1.27 1.27)
				)
				(justify mirror)
			)
		)
		(duplicate_pad_numbers_are_jumpers no)
		(fp_line
			(start -1.2954 -0.5842)
			(end -1.2954 0.5842)
			(stroke
				(width 0.1524)
				(type default)
			)
			(layer "B.SilkS")
		)
		(fp_line
			(start -1.2954 0.5842)
			(end 1.2954 0.5842)
			(stroke
				(width 0.1524)
				(type default)
			)
			(layer "B.SilkS")
		)
		(fp_line
			(start 1.2954 -0.5842)
			(end -1.2954 -0.5842)
			(stroke
				(width 0.1524)
				(type default)
			)
			(layer "B.SilkS")
		)
		(fp_line
			(start 1.2954 0.5842)
			(end 1.2954 -0.5842)
			(stroke
				(width 0.1524)
				(type default)
			)
			(layer "B.SilkS")
		)
		(fp_line
			(start -1.1938 -0.4064)
			(end -1.1938 0.4064)
			(stroke
				(width 0.1)
				(type default)
			)
			(layer "B.Fab")
		)
		(fp_line
			(start -1.1938 0.4064)
			(end -0.8636 0.4064)
			(stroke
				(width 0.1)
				(type default)
			)
			(layer "B.Fab")
		)
		(fp_line
			(start -0.8636 -0.4572)
			(end -0.8636 -0.4064)
			(stroke
				(width 0.1)
				(type default)
			)
			(layer "B.Fab")
		)
		(fp_line
			(start -0.8636 -0.4064)
			(end -1.1938 -0.4064)
			(stroke
				(width 0.1)
				(type default)
			)
			(layer "B.Fab")
		)
		(fp_line
			(start -0.8636 0.4064)
			(end -0.8636 0.4572)
			(stroke
				(width 0.1)
				(type default)
			)
			(layer "B.Fab")
		)
		(fp_line
			(start -0.8636 0.4572)
			(end 0.8636 0.4572)
			(stroke
				(width 0.1)
				(type default)
			)
			(layer "B.Fab")
		)
		(fp_line
			(start 0.8636 -0.4572)
			(end -0.8636 -0.4572)
			(stroke
				(width 0.1)
				(type default)
			)
			(layer "B.Fab")
		)
		(fp_line
			(start 0.8636 -0.4064)
			(end 0.8636 -0.4572)
			(stroke
				(width 0.1)
				(type default)
			)
			(layer "B.Fab")
		)
		(fp_line
			(start 0.8636 0.4064)
			(end 1.1938 0.4064)
			(stroke
				(width 0.1)
				(type default)
			)
			(layer "B.Fab")
		)
		(fp_line
			(start 0.8636 0.4572)
			(end 0.8636 0.4064)
			(stroke
				(width 0.1)
				(type default)
			)
			(layer "B.Fab")
		)
		(fp_line
			(start 1.1938 -0.4064)
			(end 0.8636 -0.4064)
			(stroke
				(width 0.1)
				(type default)
			)
			(layer "B.Fab")
		)
		(fp_line
			(start 1.1938 0.4064)
			(end 1.1938 -0.4064)
			(stroke
				(width 0.1)
				(type default)
			)
			(layer "B.Fab")
		)
		(pad "1" smd rect
			(at 0.7366 0 270)
			(size 0.7112 0.8128)
			(layers "B.Cu" "B.Mask" "B.Paste")
			(net "P1V8_VDDA_PEX2")
		)
		(pad "2" smd rect
			(at -0.7366 0 270)
			(size 0.7112 0.8128)
			(layers "B.Cu" "B.Mask" "B.Paste")
			(net "GND")
		)
	)
	(footprint ""
		(layer "B.Cu")
		(at 378.079 -245.872 180)
		(property "Reference" "R966"
			(at 0 0 0)
			(layer "B.SilkS")
			(hide yes)
			(effects
				(font
					(size 1.27 1.27)
				)
				(justify mirror)
			)
		)
		(property "Value" ""
			(at 0 0 0)
			(layer "B.Fab")
			(effects
				(font
					(size 1.27 1.27)
				)
				(justify mirror)
			)
		)
		(duplicate_pad_numbers_are_jumpers no)
		(fp_line
			(start 0.7874 0.4064)
			(end 0.7874 -0.4064)
			(stroke
				(width 0.1524)
				(type default)
			)
			(layer "B.SilkS")
		)
		(fp_line
			(start 0.7874 -0.4064)
			(end -0.7874 -0.4064)
			(stroke
				(width 0.1524)
				(type default)
			)
			(layer "B.SilkS")
		)
		(fp_line
			(start -0.7874 0.4064)
			(end 0.7874 0.4064)
			(stroke
				(width 0.1524)
				(type default)
			)
			(layer "B.SilkS")
		)
		(fp_line
			(start -0.7874 -0.4064)
			(end -0.7874 0.4064)
			(stroke
				(width 0.1524)
				(type default)
			)
			(layer "B.SilkS")
		)
		(fp_line
			(start 0.67945 0.3048)
			(end 0.67945 -0.305054)
			(stroke
				(width 0.1)
				(type default)
			)
			(layer "B.Fab")
		)
		(fp_line
			(start 0.67945 -0.305054)
			(end 0.12065 -0.305054)
			(stroke
				(width 0.1)
				(type default)
			)
			(layer "B.Fab")
		)
		(fp_line
			(start 0.12065 0.3048)
			(end 0.67945 0.3048)
			(stroke
				(width 0.1)
				(type default)
			)
			(layer "B.Fab")
		)
		(fp_line
			(start 0.12065 0.2794)
			(end 0.12065 0.3048)
			(stroke
				(width 0.1)
				(type default)
			)
			(layer "B.Fab")
		)
		(fp_line
			(start 0.12065 -0.2794)
			(end -0.12065 -0.2794)
			(stroke
				(width 0.1)
				(type default)
			)
			(layer "B.Fab")
		)
		(fp_line
			(start 0.12065 -0.305054)
			(end 0.12065 -0.2794)
			(stroke
				(width 0.1)
				(type default)
			)
			(layer "B.Fab")
		)
		(fp_line
			(start -0.120396 0.3048)
			(end -0.120396 0.2794)
			(stroke
				(width 0.1)
				(type default)
			)
			(layer "B.Fab")
		)
		(fp_line
			(start -0.120396 0.2794)
			(end 0.12065 0.2794)
			(stroke
				(width 0.1)
				(type default)
			)
			(layer "B.Fab")
		)
		(fp_line
			(start -0.12065 -0.2794)
			(end -0.12065 -0.3048)
			(stroke
				(width 0.1)
				(type default)
			)
			(layer "B.Fab")
		)
		(fp_line
			(start -0.12065 -0.3048)
			(end -0.67945 -0.3048)
			(stroke
				(width 0.1)
				(type default)
			)
			(layer "B.Fab")
		)
		(fp_line
			(start -0.67945 0.3048)
			(end -0.120396 0.3048)
			(stroke
				(width 0.1)
				(type default)
			)
			(layer "B.Fab")
		)
		(fp_line
			(start -0.67945 -0.3048)
			(end -0.67945 0.3048)
			(stroke
				(width 0.1)
				(type default)
			)
			(layer "B.Fab")
		)
		(pad "1" smd circle
			(at 0.40005 0)
			(size 0 0)
			(layers "B.Cu" "B.Mask" "B.Paste")
			(net "UART_PEX2_SDB_BUF_R_TX")
		)
		(pad "2" smd circle
			(at -0.40005 0)
			(size 0 0)
			(layers "B.Cu" "B.Mask" "B.Paste")
			(net "UART_PEX2_SDB_BUF_TX")
		)
	)
	(footprint ""
		(layer "B.Cu")
		(at 161.964116 -142.795752 180)
		(property "Reference" "C877"
			(at 0 0 0)
			(layer "B.SilkS")
			(hide yes)
			(effects
				(font
					(size 1.27 1.27)
				)
				(justify mirror)
			)
		)
		(property "Value" ""
			(at 0 0 0)
			(layer "B.Fab")
			(effects
				(font
					(size 1.27 1.27)
				)
				(justify mirror)
			)
		)
		(duplicate_pad_numbers_are_jumpers no)
		(fp_line
			(start 0.299974 0.150114)
			(end 0.299974 -0.150114)
			(stroke
				(width 0.1)
				(type default)
			)
			(layer "B.Fab")
		)
		(fp_line
			(start 0.299974 -0.150114)
			(end -0.299974 -0.150114)
			(stroke
				(width 0.1)
				(type default)
			)
			(layer "B.Fab")
		)
		(fp_line
			(start -0.299974 0.150114)
			(end 0.299974 0.150114)
			(stroke
				(width 0.1)
				(type default)
			)
			(layer "B.Fab")
		)
		(fp_line
			(start -0.299974 -0.150114)
			(end -0.299974 0.150114)
			(stroke
				(width 0.1)
				(type default)
			)
			(layer "B.Fab")
		)
		(pad "1" smd rect
			(at 0.2667 0)
			(size 0.3048 0.381)
			(layers "B.Cu" "B.Mask" "B.Paste")
			(net "P12V_NIC2")
		)
		(pad "2" smd rect
			(at -0.2667 0)
			(size 0.3048 0.381)
			(layers "B.Cu" "B.Mask" "B.Paste")
			(net "GND")
		)
	)
	(footprint ""
		(layer "B.Cu")
		(at 65.349882 -288.299906 90)
		(property "Reference" "C2936"
			(at 0 0 90)
			(layer "B.SilkS")
			(hide yes)
			(effects
				(font
					(size 1.27 1.27)
				)
				(justify mirror)
			)
		)
		(property "Value" ""
			(at 0 0 90)
			(layer "B.Fab")
			(effects
				(font
					(size 1.27 1.27)
				)
				(justify mirror)
			)
		)
		(duplicate_pad_numbers_are_jumpers no)
		(fp_line
			(start 0.299974 -0.150114)
			(end -0.299974 -0.150114)
			(stroke
				(width 0.1)
				(type default)
			)
			(layer "B.Fab")
		)
		(fp_line
			(start -0.299974 -0.150114)
			(end -0.299974 0.150114)
			(stroke
				(width 0.1)
				(type default)
			)
			(layer "B.Fab")
		)
		(fp_line
			(start 0.299974 0.150114)
			(end 0.299974 -0.150114)
			(stroke
				(width 0.1)
				(type default)
			)
			(layer "B.Fab")
		)
		(fp_line
			(start -0.299974 0.150114)
			(end 0.299974 0.150114)
			(stroke
				(width 0.1)
				(type default)
			)
			(layer "B.Fab")
		)
		(pad "1" smd rect
			(at 0.2667 0 270)
			(size 0.3048 0.381)
			(layers "B.Cu" "B.Mask" "B.Paste")
			(net "P1V25_PEX0")
		)
		(pad "2" smd rect
			(at -0.2667 0 270)
			(size 0.3048 0.381)
			(layers "B.Cu" "B.Mask" "B.Paste")
			(net "GND")
		)
	)
)
